(kicad_pcb
	(version 20260206)
	(generator "pcbnew")
	(generator_version "10.0")
	(general
		(thickness 1.6)
		(legacy_teardrops no)
	)
	(paper "A4")
	(title_block
		(title "01162023_DA0F0TEBIF0_F0T_Expander_BD_F_brd_V02_OCP.brd")
		(comment 1 "Grand Teton / footprints 7094-7100 of 9728")
	)
	(layers
		(0 "F.Cu" signal "TOP")
		(4 "In1.Cu" signal "GND")
		(6 "In2.Cu" signal "VCC")
		(8 "In3.Cu" signal "VCC1")
		(10 "In4.Cu" signal "GND1")
		(12 "In5.Cu" signal "IN1")
		(14 "In6.Cu" signal "GND2")
		(16 "In7.Cu" signal "IN2")
		(18 "In8.Cu" signal "GND3")
		(20 "In9.Cu" signal "IN3")
		(22 "In10.Cu" signal "GND4")
		(24 "In11.Cu" signal "IN4")
		(26 "In12.Cu" signal "GND5")
		(28 "In13.Cu" signal "IN5")
		(30 "In14.Cu" signal "GND6")
		(32 "In15.Cu" signal "IN6")
		(34 "In16.Cu" signal "GND7")
		(2 "B.Cu" signal "BOTTOM")
		(9 "F.Adhes" user "F.Adhesive")
		(11 "B.Adhes" user "B.Adhesive")
		(13 "F.Paste" user "Package Geometry/Pastemask Top")
		(15 "B.Paste" user "Package Geometry/Pastemask Bottom")
		(5 "F.SilkS" user "Ref Des/Silkscreen Top")
		(7 "B.SilkS" user "Ref Des/Silkscreen Bottom")
		(1 "F.Mask" user "Board Geometry/Soldermask Top")
		(3 "B.Mask" user "Board Geometry/Soldermask Bottom")
		(17 "Dwgs.User" user "User.Drawings")
		(19 "Cmts.User" user "User.Comments")
		(21 "Eco1.User" user "User.Eco1")
		(23 "Eco2.User" user "User.Eco2")
		(25 "Edge.Cuts" user "Board Geometry/Outline")
		(27 "Margin" user)
		(31 "F.CrtYd" user "Package Geometry/Place Bound Top")
		(29 "B.CrtYd" user "Package Geometry/Place Bound Bottom")
		(35 "F.Fab" user "Ref Des/Assembly Top")
		(33 "B.Fab" user "Ref Des/Assembly Bottom")
	)
	(footprint ""
		(layer "F.Cu")
		(at 26.930096 -281.203908 -90)
		(property "Reference" "C3037"
			(at 0 0 270)
			(layer "F.SilkS")
			(hide yes)
			(effects
				(font
					(size 1.27 1.27)
				)
			)
		)
		(property "Value" ""
			(at 0 0 270)
			(layer "F.Fab")
			(effects
				(font
					(size 1.27 1.27)
				)
			)
		)
		(duplicate_pad_numbers_are_jumpers no)
		(fp_line
			(start -1.2954 0.5842)
			(end -1.2954 -0.5842)
			(stroke
				(width 0.1524)
				(type default)
			)
			(layer "F.SilkS")
		)
		(fp_line
			(start 1.2954 0.5842)
			(end -1.2954 0.5842)
			(stroke
				(width 0.1524)
				(type default)
			)
			(layer "F.SilkS")
		)
		(fp_line
			(start -1.2954 -0.5842)
			(end 1.2954 -0.5842)
			(stroke
				(width 0.1524)
				(type default)
			)
			(layer "F.SilkS")
		)
		(fp_line
			(start 1.2954 -0.5842)
			(end 1.2954 0.5842)
			(stroke
				(width 0.1524)
				(type default)
			)
			(layer "F.SilkS")
		)
		(fp_line
			(start -0.8636 0.4572)
			(end -0.8636 0.4064)
			(stroke
				(width 0.1)
				(type default)
			)
			(layer "F.Fab")
		)
		(fp_line
			(start 0.8636 0.4572)
			(end -0.8636 0.4572)
			(stroke
				(width 0.1)
				(type default)
			)
			(layer "F.Fab")
		)
		(fp_line
			(start -1.1938 0.4064)
			(end -1.1938 -0.4064)
			(stroke
				(width 0.1)
				(type default)
			)
			(layer "F.Fab")
		)
		(fp_line
			(start -0.8636 0.4064)
			(end -1.1938 0.4064)
			(stroke
				(width 0.1)
				(type default)
			)
			(layer "F.Fab")
		)
		(fp_line
			(start 0.8636 0.4064)
			(end 0.8636 0.4572)
			(stroke
				(width 0.1)
				(type default)
			)
			(layer "F.Fab")
		)
		(fp_line
			(start 1.1938 0.4064)
			(end 0.8636 0.4064)
			(stroke
				(width 0.1)
				(type default)
			)
			(layer "F.Fab")
		)
		(fp_line
			(start -1.1938 -0.4064)
			(end -0.8636 -0.4064)
			(stroke
				(width 0.1)
				(type default)
			)
			(layer "F.Fab")
		)
		(fp_line
			(start -0.8636 -0.4064)
			(end -0.8636 -0.4572)
			(stroke
				(width 0.1)
				(type default)
			)
			(layer "F.Fab")
		)
		(fp_line
			(start 0.8636 -0.4064)
			(end 1.1938 -0.4064)
			(stroke
				(width 0.1)
				(type default)
			)
			(layer "F.Fab")
		)
		(fp_line
			(start 1.1938 -0.4064)
			(end 1.1938 0.4064)
			(stroke
				(width 0.1)
				(type default)
			)
			(layer "F.Fab")
		)
		(fp_line
			(start -0.8636 -0.4572)
			(end 0.8636 -0.4572)
			(stroke
				(width 0.1)
				(type default)
			)
			(layer "F.Fab")
		)
		(fp_line
			(start 0.8636 -0.4572)
			(end 0.8636 -0.4064)
			(stroke
				(width 0.1)
				(type default)
			)
			(layer "F.Fab")
		)
		(pad "1" smd rect
			(at -0.7366 0 180)
			(size 0.7112 0.8128)
			(layers "F.Cu" "F.Mask" "F.Paste")
			(net "P1V8_PLL0_PEX0")
		)
		(pad "2" smd rect
			(at 0.7366 0 180)
			(size 0.7112 0.8128)
			(layers "F.Cu" "F.Mask" "F.Paste")
			(net "GND")
		)
	)
	(footprint ""
		(layer "F.Cu")
		(at 86.943692 -302.873664 -90)
		(property "Reference" "R6806"
			(at 0 0 270)
			(layer "F.SilkS")
			(hide yes)
			(effects
				(font
					(size 1.27 1.27)
				)
			)
		)
		(property "Value" ""
			(at 0 0 270)
			(layer "F.Fab")
			(effects
				(font
					(size 1.27 1.27)
				)
			)
		)
		(duplicate_pad_numbers_are_jumpers no)
		(fp_line
			(start -0.7874 0.4064)
			(end -0.7874 -0.4064)
			(stroke
				(width 0.1524)
				(type default)
			)
			(layer "F.SilkS")
		)
		(fp_line
			(start 0.7874 0.4064)
			(end -0.7874 0.4064)
			(stroke
				(width 0.1524)
				(type default)
			)
			(layer "F.SilkS")
		)
		(fp_line
			(start -0.7874 -0.4064)
			(end 0.7874 -0.4064)
			(stroke
				(width 0.1524)
				(type default)
			)
			(layer "F.SilkS")
		)
		(fp_line
			(start 0.7874 -0.4064)
			(end 0.7874 0.4064)
			(stroke
				(width 0.1524)
				(type default)
			)
			(layer "F.SilkS")
		)
		(fp_line
			(start -0.67945 0.3048)
			(end -0.67945 -0.305054)
			(stroke
				(width 0.1)
				(type default)
			)
			(layer "F.Fab")
		)
		(fp_line
			(start -0.12065 0.3048)
			(end -0.67945 0.3048)
			(stroke
				(width 0.1)
				(type default)
			)
			(layer "F.Fab")
		)
		(fp_line
			(start 0.120396 0.3048)
			(end 0.120396 0.2794)
			(stroke
				(width 0.1)
				(type default)
			)
			(layer "F.Fab")
		)
		(fp_line
			(start 0.67945 0.3048)
			(end 0.120396 0.3048)
			(stroke
				(width 0.1)
				(type default)
			)
			(layer "F.Fab")
		)
		(fp_line
			(start -0.12065 0.2794)
			(end -0.12065 0.3048)
			(stroke
				(width 0.1)
				(type default)
			)
			(layer "F.Fab")
		)
		(fp_line
			(start 0.120396 0.2794)
			(end -0.12065 0.2794)
			(stroke
				(width 0.1)
				(type default)
			)
			(layer "F.Fab")
		)
		(fp_line
			(start -0.12065 -0.2794)
			(end 0.12065 -0.2794)
			(stroke
				(width 0.1)
				(type default)
			)
			(layer "F.Fab")
		)
		(fp_line
			(start 0.12065 -0.2794)
			(end 0.12065 -0.3048)
			(stroke
				(width 0.1)
				(type default)
			)
			(layer "F.Fab")
		)
		(fp_line
			(start 0.12065 -0.3048)
			(end 0.67945 -0.3048)
			(stroke
				(width 0.1)
				(type default)
			)
			(layer "F.Fab")
		)
		(fp_line
			(start 0.67945 -0.3048)
			(end 0.67945 0.3048)
			(stroke
				(width 0.1)
				(type default)
			)
			(layer "F.Fab")
		)
		(fp_line
			(start -0.67945 -0.305054)
			(end -0.12065 -0.305054)
			(stroke
				(width 0.1)
				(type default)
			)
			(layer "F.Fab")
		)
		(fp_line
			(start -0.12065 -0.305054)
			(end -0.12065 -0.2794)
			(stroke
				(width 0.1)
				(type default)
			)
			(layer "F.Fab")
		)
		(pad "1" smd circle
			(at -0.40005 0 270)
			(size 0 0)
			(layers "F.Cu" "F.Mask" "F.Paste")
			(net "SMB_PEX0_R_SCL")
		)
		(pad "2" smd circle
			(at 0.40005 0 270)
			(size 0 0)
			(layers "F.Cu" "F.Mask" "F.Paste")
			(net "SMB_PEX0_SCL")
		)
	)
	(footprint ""
		(layer "F.Cu")
		(at 268.838426 -108.29544)
		(property "Reference" "C475"
			(at 0 0 0)
			(layer "F.SilkS")
			(hide yes)
			(effects
				(font
					(size 1.27 1.27)
				)
			)
		)
		(property "Value" ""
			(at 0 0 0)
			(layer "F.Fab")
			(effects
				(font
					(size 1.27 1.27)
				)
			)
		)
		(duplicate_pad_numbers_are_jumpers no)
		(fp_line
			(start -0.299974 -0.150114)
			(end 0.299974 -0.150114)
			(stroke
				(width 0.1)
				(type default)
			)
			(layer "F.Fab")
		)
		(fp_line
			(start -0.299974 0.150114)
			(end -0.299974 -0.150114)
			(stroke
				(width 0.1)
				(type default)
			)
			(layer "F.Fab")
		)
		(fp_line
			(start 0.299974 -0.150114)
			(end 0.299974 0.150114)
			(stroke
				(width 0.1)
				(type default)
			)
			(layer "F.Fab")
		)
		(fp_line
			(start 0.299974 0.150114)
			(end -0.299974 0.150114)
			(stroke
				(width 0.1)
				(type default)
			)
			(layer "F.Fab")
		)
		(pad "1" smd rect
			(at -0.2667 0)
			(size 0.3048 0.381)
			(layers "F.Cu" "F.Mask" "F.Paste")
			(net "P5E_PEX2_STN1_TX_DN<21>")
		)
		(pad "2" smd rect
			(at 0.2667 0)
			(size 0.3048 0.381)
			(layers "F.Cu" "F.Mask" "F.Paste")
			(net "P5E_PEX2_STN1_TX_C_DN<21>")
		)
	)
	(footprint ""
		(layer "F.Cu")
		(at 450.230494 -121.80824 180)
		(property "Reference" "R6053"
			(at 0 0 180)
			(layer "F.SilkS")
			(hide yes)
			(effects
				(font
					(size 1.27 1.27)
				)
			)
		)
		(property "Value" ""
			(at 0 0 180)
			(layer "F.Fab")
			(effects
				(font
					(size 1.27 1.27)
				)
			)
		)
		(duplicate_pad_numbers_are_jumpers no)
		(fp_line
			(start 0.7874 0.4064)
			(end -0.7874 0.4064)
			(stroke
				(width 0.1524)
				(type default)
			)
			(layer "F.SilkS")
		)
		(fp_line
			(start 0.7874 -0.4064)
			(end 0.7874 0.4064)
			(stroke
				(width 0.1524)
				(type default)
			)
			(layer "F.SilkS")
		)
		(fp_line
			(start -0.7874 0.4064)
			(end -0.7874 -0.4064)
			(stroke
				(width 0.1524)
				(type default)
			)
			(layer "F.SilkS")
		)
		(fp_line
			(start -0.7874 -0.4064)
			(end 0.7874 -0.4064)
			(stroke
				(width 0.1524)
				(type default)
			)
			(layer "F.SilkS")
		)
		(fp_line
			(start 0.67945 0.3048)
			(end 0.120396 0.3048)
			(stroke
				(width 0.1)
				(type default)
			)
			(layer "F.Fab")
		)
		(fp_line
			(start 0.67945 -0.3048)
			(end 0.67945 0.3048)
			(stroke
				(width 0.1)
				(type default)
			)
			(layer "F.Fab")
		)
		(fp_line
			(start 0.12065 -0.2794)
			(end 0.12065 -0.3048)
			(stroke
				(width 0.1)
				(type default)
			)
			(layer "F.Fab")
		)
		(fp_line
			(start 0.12065 -0.3048)
			(end 0.67945 -0.3048)
			(stroke
				(width 0.1)
				(type default)
			)
			(layer "F.Fab")
		)
		(fp_line
			(start 0.120396 0.3048)
			(end 0.120396 0.2794)
			(stroke
				(width 0.1)
				(type default)
			)
			(layer "F.Fab")
		)
		(fp_line
			(start 0.120396 0.2794)
			(end -0.12065 0.2794)
			(stroke
				(width 0.1)
				(type default)
			)
			(layer "F.Fab")
		)
		(fp_line
			(start -0.12065 0.3048)
			(end -0.67945 0.3048)
			(stroke
				(width 0.1)
				(type default)
			)
			(layer "F.Fab")
		)
		(fp_line
			(start -0.12065 0.2794)
			(end -0.12065 0.3048)
			(stroke
				(width 0.1)
				(type default)
			)
			(layer "F.Fab")
		)
		(fp_line
			(start -0.12065 -0.2794)
			(end 0.12065 -0.2794)
			(stroke
				(width 0.1)
				(type default)
			)
			(layer "F.Fab")
		)
		(fp_line
			(start -0.12065 -0.305054)
			(end -0.12065 -0.2794)
			(stroke
				(width 0.1)
				(type default)
			)
			(layer "F.Fab")
		)
		(fp_line
			(start -0.67945 0.3048)
			(end -0.67945 -0.305054)
			(stroke
				(width 0.1)
				(type default)
			)
			(layer "F.Fab")
		)
		(fp_line
			(start -0.67945 -0.305054)
			(end -0.12065 -0.305054)
			(stroke
				(width 0.1)
				(type default)
			)
			(layer "F.Fab")
		)
		(pad "1" smd circle
			(at -0.40005 0 180)
			(size 0 0)
			(layers "F.Cu" "F.Mask" "F.Paste")
			(net "P3V3_NIC7_PG_G1")
		)
		(pad "2" smd circle
			(at 0.40005 0 180)
			(size 0 0)
			(layers "F.Cu" "F.Mask" "F.Paste")
			(net "GND")
		)
	)
	(footprint ""
		(layer "F.Cu")
		(at 203.00442 -306.077874 -90)
		(property "Reference" "R6807"
			(at 0 0 270)
			(layer "F.SilkS")
			(hide yes)
			(effects
				(font
					(size 1.27 1.27)
				)
			)
		)
		(property "Value" ""
			(at 0 0 270)
			(layer "F.Fab")
			(effects
				(font
					(size 1.27 1.27)
				)
			)
		)
		(duplicate_pad_numbers_are_jumpers no)
		(fp_line
			(start -0.7874 0.4064)
			(end -0.7874 -0.4064)
			(stroke
				(width 0.1524)
				(type default)
			)
			(layer "F.SilkS")
		)
		(fp_line
			(start 0.7874 0.4064)
			(end -0.7874 0.4064)
			(stroke
				(width 0.1524)
				(type default)
			)
			(layer "F.SilkS")
		)
		(fp_line
			(start -0.7874 -0.4064)
			(end 0.7874 -0.4064)
			(stroke
				(width 0.1524)
				(type default)
			)
			(layer "F.SilkS")
		)
		(fp_line
			(start 0.7874 -0.4064)
			(end 0.7874 0.4064)
			(stroke
				(width 0.1524)
				(type default)
			)
			(layer "F.SilkS")
		)
		(fp_line
			(start -0.67945 0.3048)
			(end -0.67945 -0.305054)
			(stroke
				(width 0.1)
				(type default)
			)
			(layer "F.Fab")
		)
		(fp_line
			(start -0.12065 0.3048)
			(end -0.67945 0.3048)
			(stroke
				(width 0.1)
				(type default)
			)
			(layer "F.Fab")
		)
		(fp_line
			(start 0.120396 0.3048)
			(end 0.120396 0.2794)
			(stroke
				(width 0.1)
				(type default)
			)
			(layer "F.Fab")
		)
		(fp_line
			(start 0.67945 0.3048)
			(end 0.120396 0.3048)
			(stroke
				(width 0.1)
				(type default)
			)
			(layer "F.Fab")
		)
		(fp_line
			(start -0.12065 0.2794)
			(end -0.12065 0.3048)
			(stroke
				(width 0.1)
				(type default)
			)
			(layer "F.Fab")
		)
		(fp_line
			(start 0.120396 0.2794)
			(end -0.12065 0.2794)
			(stroke
				(width 0.1)
				(type default)
			)
			(layer "F.Fab")
		)
		(fp_line
			(start -0.12065 -0.2794)
			(end 0.12065 -0.2794)
			(stroke
				(width 0.1)
				(type default)
			)
			(layer "F.Fab")
		)
		(fp_line
			(start 0.12065 -0.2794)
			(end 0.12065 -0.3048)
			(stroke
				(width 0.1)
				(type default)
			)
			(layer "F.Fab")
		)
		(fp_line
			(start 0.12065 -0.3048)
			(end 0.67945 -0.3048)
			(stroke
				(width 0.1)
				(type default)
			)
			(layer "F.Fab")
		)
		(fp_line
			(start 0.67945 -0.3048)
			(end 0.67945 0.3048)
			(stroke
				(width 0.1)
				(type default)
			)
			(layer "F.Fab")
		)
		(fp_line
			(start -0.67945 -0.305054)
			(end -0.12065 -0.305054)
			(stroke
				(width 0.1)
				(type default)
			)
			(layer "F.Fab")
		)
		(fp_line
			(start -0.12065 -0.305054)
			(end -0.12065 -0.2794)
			(stroke
				(width 0.1)
				(type default)
			)
			(layer "F.Fab")
		)
		(pad "1" smd circle
			(at -0.40005 0 270)
			(size 0 0)
			(layers "F.Cu" "F.Mask" "F.Paste")
			(net "SMB_PEX1_R_SDA")
		)
		(pad "2" smd circle
			(at 0.40005 0 270)
			(size 0 0)
			(layers "F.Cu" "F.Mask" "F.Paste")
			(net "SMB_PEX1_SDA")
		)
	)
	(footprint ""
		(layer "F.Cu")
		(at 406.054306 -48.21809)
		(property "Reference" "PD73"
			(at -3.362706 2.24536 0)
			(unlocked yes)
			(layer "F.SilkS")
			(effects
				(font
					(size 0.7874 0.5842)
					(thickness 0.1524)
				)
				(justify left)
			)
		)
		(property "Value" ""
			(at 0 0 0)
			(layer "F.Fab")
			(effects
				(font
					(size 1.27 1.27)
				)
			)
		)
		(duplicate_pad_numbers_are_jumpers no)
		(fp_line
			(start -3.400044 -1.459992)
			(end 4.107942 -1.459992)
			(stroke
				(width 0.1524)
				(type default)
			)
			(layer "F.SilkS")
		)
		(fp_line
			(start -3.400044 1.459992)
			(end -3.400044 -1.459992)
			(stroke
				(width 0.1524)
				(type default)
			)
			(layer "F.SilkS")
		)
		(fp_line
			(start 4.107942 -1.459992)
			(end 4.107942 1.459992)
			(stroke
				(width 0.1524)
				(type default)
			)
			(layer "F.SilkS")
		)
		(fp_line
			(start 4.107942 1.459992)
			(end -3.400044 1.459992)
			(stroke
				(width 0.1524)
				(type default)
			)
			(layer "F.SilkS")
		)
		(fp_poly
			(pts
				(xy 4.107942 -1.459992) (xy 4.107942 1.459992) (xy 3.308096 1.459992) (xy 3.308096 -1.459992)
			)
			(stroke
				(width 0)
				(type default)
			)
			(fill yes)
			(layer "F.SilkS")
		)
		(fp_line
			(start -2.29997 -1.459992)
			(end 2.29997 -1.459992)
			(stroke
				(width 0.1)
				(type default)
			)
			(layer "F.Fab")
		)
		(fp_line
			(start -2.29997 1.459992)
			(end -2.29997 -1.459992)
			(stroke
				(width 0.1)
				(type default)
			)
			(layer "F.Fab")
		)
		(fp_line
			(start 2.29997 -1.459992)
			(end 2.29997 1.459992)
			(stroke
				(width 0.1)
				(type default)
			)
			(layer "F.Fab")
		)
		(fp_line
			(start 2.29997 1.459992)
			(end -2.29997 1.459992)
			(stroke
				(width 0.1)
				(type default)
			)
			(layer "F.Fab")
		)
		(fp_text user "+"
			(at -4.7752 -0.12065 0)
			(unlocked yes)
			(layer "F.SilkS")
			(effects
				(font
					(size 1.905 1.4224)
					(thickness 0.1524)
				)
				(justify left)
			)
		)
		(fp_text user "-"
			(at 5.4102 0.29845 180)
			(unlocked yes)
			(layer "F.SilkS")
			(effects
				(font
					(size 1.905 1.4224)
					(thickness 0.1524)
				)
				(justify left)
			)
		)
		(fp_text user "+"
			(at -4.7752 -0.12065 0)
			(unlocked yes)
			(layer "F.Fab")
			(effects
				(font
					(size 1.905 1.4224)
					(thickness 0.1524)
				)
				(justify left)
			)
		)
		(fp_text user "-"
			(at 5.4102 0.29845 180)
			(unlocked yes)
			(layer "F.Fab")
			(effects
				(font
					(size 1.905 1.4224)
					(thickness 0.1524)
				)
				(justify left)
			)
		)
		(pad "A" smd rect
			(at -1.999996 0 90)
			(size 1.7018 2.5146)
			(layers "F.Cu" "F.Mask" "F.Paste")
			(net "GND")
		)
		(pad "C" smd rect
			(at 1.999996 0 90)
			(size 1.7018 2.5146)
			(layers "F.Cu" "F.Mask" "F.Paste")
			(net "P3V3_SSD14")
		)
	)
	(footprint ""
		(layer "F.Cu")
		(at 117.958362 -130.217926)
		(property "Reference" "C2852"
			(at 0 0 0)
			(layer "F.SilkS")
			(hide yes)
			(effects
				(font
					(size 1.27 1.27)
				)
			)
		)
		(property "Value" ""
			(at 0 0 0)
			(layer "F.Fab")
			(effects
				(font
					(size 1.27 1.27)
				)
			)
		)
		(duplicate_pad_numbers_are_jumpers no)
		(fp_line
			(start -0.7874 -0.4064)
			(end 0.7874 -0.4064)
			(stroke
				(width 0.1524)
				(type default)
			)
			(layer "F.SilkS")
		)
		(fp_line
			(start -0.7874 0.4064)
			(end -0.7874 -0.4064)
			(stroke
				(width 0.1524)
				(type default)
			)
			(layer "F.SilkS")
		)
		(fp_line
			(start 0.7874 -0.4064)
			(end 0.7874 0.4064)
			(stroke
				(width 0.1524)
				(type default)
			)
			(layer "F.SilkS")
		)
		(fp_line
			(start 0.7874 0.4064)
			(end -0.7874 0.4064)
			(stroke
				(width 0.1524)
				(type default)
			)
			(layer "F.SilkS")
		)
		(fp_line
			(start -0.67945 -0.305054)
			(end -0.12065 -0.305054)
			(stroke
				(width 0.1)
				(type default)
			)
			(layer "F.Fab")
		)
		(fp_line
			(start -0.67945 0.3048)
			(end -0.67945 -0.305054)
			(stroke
				(width 0.1)
				(type default)
			)
			(layer "F.Fab")
		)
		(fp_line
			(start -0.12065 -0.305054)
			(end -0.12065 -0.2794)
			(stroke
				(width 0.1)
				(type default)
			)
			(layer "F.Fab")
		)
		(fp_line
			(start -0.12065 -0.2794)
			(end 0.12065 -0.2794)
			(stroke
				(width 0.1)
				(type default)
			)
			(layer "F.Fab")
		)
		(fp_line
			(start -0.12065 0.2794)
			(end -0.12065 0.3048)
			(stroke
				(width 0.1)
				(type default)
			)
			(layer "F.Fab")
		)
		(fp_line
			(start -0.12065 0.3048)
			(end -0.67945 0.3048)
			(stroke
				(width 0.1)
				(type default)
			)
			(layer "F.Fab")
		)
		(fp_line
			(start 0.120396 0.2794)
			(end -0.12065 0.2794)
			(stroke
				(width 0.1)
				(type default)
			)
			(layer "F.Fab")
		)
		(fp_line
			(start 0.120396 0.3048)
			(end 0.120396 0.2794)
			(stroke
				(width 0.1)
				(type default)
			)
			(layer "F.Fab")
		)
		(fp_line
			(start 0.12065 -0.3048)
			(end 0.67945 -0.3048)
			(stroke
				(width 0.1)
				(type default)
			)
			(layer "F.Fab")
		)
		(fp_line
			(start 0.12065 -0.2794)
			(end 0.12065 -0.3048)
			(stroke
				(width 0.1)
				(type default)
			)
			(layer "F.Fab")
		)
		(fp_line
			(start 0.67945 -0.3048)
			(end 0.67945 0.3048)
			(stroke
				(width 0.1)
				(type default)
			)
			(layer "F.Fab")
		)
		(fp_line
			(start 0.67945 0.3048)
			(end 0.120396 0.3048)
			(stroke
				(width 0.1)
				(type default)
			)
			(layer "F.Fab")
		)
		(pad "1" smd circle
			(at -0.40005 0)
			(size 0 0)
			(layers "F.Cu" "F.Mask" "F.Paste")
			(net "PWR_EN_P3V3_R")
		)
		(pad "2" smd circle
			(at 0.40005 0)
			(size 0 0)
			(layers "F.Cu" "F.Mask" "F.Paste")
			(net "GND")
		)
	)
)
